(kicad_pcb
	(version 20260206)
	(generator "pcbnew")
	(generator_version "10.0")
	(general
		(thickness 1.6)
		(legacy_teardrops no)
	)
	(paper "A4")
	(title_block
		(title "Bryce Canyon_F.DPB_16315-1-OCP.brd")
		(comment 1 "Bryce Canyon / footprints 30-37 of 2223")
	)
	(layers
		(0 "F.Cu" signal "TOP")
		(4 "In1.Cu" signal "L2GND")
		(6 "In2.Cu" signal "L3")
		(8 "In3.Cu" signal "L4GND")
		(10 "In4.Cu" signal "L5")
		(12 "In5.Cu" signal "L6VCC")
		(14 "In6.Cu" signal "L7VCC")
		(16 "In7.Cu" signal "L8")
		(18 "In8.Cu" signal "L9GND")
		(20 "In9.Cu" signal "L10")
		(22 "In10.Cu" signal "L11GND")
		(2 "B.Cu" signal "BOTTOM")
		(9 "F.Adhes" user "F.Adhesive")
		(11 "B.Adhes" user "B.Adhesive")
		(13 "F.Paste" user "Package Geometry/Pastemask Top")
		(15 "B.Paste" user "Package Geometry/Pastemask Bottom")
		(5 "F.SilkS" user "Ref Des/Silkscreen Top")
		(7 "B.SilkS" user "Ref Des/Silkscreen Bottom")
		(1 "F.Mask" user "Board Geometry/Soldermask Top")
		(3 "B.Mask" user "Board Geometry/Soldermask Bottom")
		(17 "Dwgs.User" user "User.Drawings")
		(19 "Cmts.User" user "User.Comments")
		(21 "Eco1.User" user "User.Eco1")
		(23 "Eco2.User" user "User.Eco2")
		(25 "Edge.Cuts" user "Board Geometry/Outline")
		(27 "Margin" user)
		(31 "F.CrtYd" user "Package Geometry/Place Bound Top")
		(29 "B.CrtYd" user "Package Geometry/Place Bound Bottom")
		(35 "F.Fab" user "Ref Des/Assembly Top")
		(33 "B.Fab" user "Ref Des/Assembly Bottom")
	)
	(footprint ""
		(layer "F.Cu")
		(at 440.738514 -290.951412 90)
		(property "Reference" "R595"
			(at 0 0 90)
			(layer "F.SilkS")
			(hide yes)
			(effects
				(font
					(size 1.27 1.27)
				)
			)
		)
		(property "Value" "4K7R2J-2-GP"
			(at 0.064008 -3.993896 90)
			(unlocked yes)
			(layer "F.Fab")
			(hide yes)
			(effects
				(font
					(size 1.016 1.016)
					(thickness 0.1524)
				)
			)
		)
		(property "Device Type" "R402H16"
			(at 0.064008 -5.517896 90)
			(unlocked yes)
			(layer "F.Fab")
			(hide yes)
			(effects
				(font
					(size 1.016 1.016)
					(thickness 0.1524)
				)
			)
		)
		(duplicate_pad_numbers_are_jumpers no)
		(fp_line
			(start 0.508 -0.9398)
			(end -0.508 -0.9398)
			(stroke
				(width 0.1524)
				(type default)
			)
			(layer "F.SilkS")
		)
		(fp_line
			(start -0.508 -0.9398)
			(end -0.508 0.9398)
			(stroke
				(width 0.1524)
				(type default)
			)
			(layer "F.SilkS")
		)
		(fp_rect
			(start -0.508 0.9398)
			(end 0.508 -0.9398)
			(stroke
				(width 0)
				(type default)
			)
			(fill no)
			(layer "F.CrtYd")
		)
		(fp_rect
			(start -0.508 0.9398)
			(end 0.508 -0.9398)
			(stroke
				(width 0)
				(type default)
			)
			(fill no)
			(layer "F.Fab")
		)
		(pad "1" smd custom
			(at 0 -0.4445 90)
			(size 0.1397 0.1397)
			(layers "F.Cu" "F.Mask" "F.Paste")
			(net "DRIVE_B_34_FLT_LED")
			(options
				(clearance outline)
				(anchor circle)
			)
			(primitives
				(gr_poly
					(pts
						(arc
							(start -0.1778 -0.2794)
							(mid -0.249642 -0.249642)
							(end -0.2794 -0.1778)
						)
						(arc
							(start -0.2794 0.1778)
							(mid -0.249642 0.249642)
							(end -0.1778 0.2794)
						)
						(arc
							(start 0.1778 0.2794)
							(mid 0.249642 0.249642)
							(end 0.2794 0.1778)
						)
						(arc
							(start 0.2794 -0.1778)
							(mid 0.249642 -0.249642)
							(end 0.1778 -0.2794)
						)
					)
					(width 0)
					(fill yes)
				)
			)
		)
		(pad "2" smd custom
			(at 0 0.4445 90)
			(size 0.1397 0.1397)
			(layers "F.Cu" "F.Mask" "F.Paste")
			(net "GND")
			(options
				(clearance outline)
				(anchor circle)
			)
			(primitives
				(gr_poly
					(pts
						(arc
							(start -0.1778 -0.2794)
							(mid -0.249642 -0.249642)
							(end -0.2794 -0.1778)
						)
						(arc
							(start -0.2794 0.1778)
							(mid -0.249642 0.249642)
							(end -0.1778 0.2794)
						)
						(arc
							(start 0.1778 0.2794)
							(mid 0.249642 0.249642)
							(end 0.2794 0.1778)
						)
						(arc
							(start 0.2794 -0.1778)
							(mid 0.249642 -0.249642)
							(end 0.1778 -0.2794)
						)
					)
					(width 0)
					(fill yes)
				)
			)
		)
	)
	(footprint ""
		(layer "F.Cu")
		(at 32.463486 -43.660568 90)
		(property "Reference" "C351"
			(at 0 0 90)
			(layer "F.SilkS")
			(hide yes)
			(effects
				(font
					(size 1.27 1.27)
				)
			)
		)
		(property "Value" "SCD01U16V1KX-GP"
			(at -2.8321 -1.7399 90)
			(unlocked yes)
			(layer "F.Fab")
			(hide yes)
			(effects
				(font
					(size 1.016 1.016)
					(thickness 0.1524)
				)
			)
		)
		(property "Device Type" "C0201H13"
			(at -2.8321 -3.2639 90)
			(unlocked yes)
			(layer "F.Fab")
			(hide yes)
			(effects
				(font
					(size 1.016 1.016)
					(thickness 0.1524)
				)
			)
		)
		(duplicate_pad_numbers_are_jumpers no)
		(fp_rect
			(start -0.2794 0.6477)
			(end 0.2794 -0.6477)
			(stroke
				(width 0)
				(type default)
			)
			(fill no)
			(layer "F.CrtYd")
		)
		(fp_rect
			(start -0.2794 0.6477)
			(end 0.2794 -0.6477)
			(stroke
				(width 0)
				(type default)
			)
			(fill no)
			(layer "F.Fab")
		)
		(pad "1" smd custom
			(at 0 -0.2794 90)
			(size 0.0762 0.0762)
			(layers "F.Cu" "F.Mask" "F.Paste")
			(net "SAS_HDD_RX_P24")
			(options
				(clearance outline)
				(anchor circle)
			)
			(primitives
				(gr_poly
					(pts
						(arc
							(start 0.1524 -0.127)
							(mid 0.137521 -0.162921)
							(end 0.1016 -0.1778)
						)
						(arc
							(start -0.1016 -0.1778)
							(mid -0.137521 -0.162921)
							(end -0.1524 -0.127)
						)
						(arc
							(start -0.1524 0.127)
							(mid -0.137521 0.162921)
							(end -0.1016 0.1778)
						)
						(arc
							(start 0.1016 0.1778)
							(mid 0.137521 0.162921)
							(end 0.1524 0.127)
						)
					)
					(width 0)
					(fill yes)
				)
			)
		)
		(pad "2" smd custom
			(at 0 0.2794 90)
			(size 0.0762 0.0762)
			(layers "F.Cu" "F.Mask" "F.Paste")
			(net "PHY_SCC_A_TO_DRV_A_24_DP")
			(options
				(clearance outline)
				(anchor circle)
			)
			(primitives
				(gr_poly
					(pts
						(arc
							(start 0.1524 -0.127)
							(mid 0.137521 -0.162921)
							(end 0.1016 -0.1778)
						)
						(arc
							(start -0.1016 -0.1778)
							(mid -0.137521 -0.162921)
							(end -0.1524 -0.127)
						)
						(arc
							(start -0.1524 0.127)
							(mid -0.137521 0.162921)
							(end -0.1016 0.1778)
						)
						(arc
							(start 0.1016 0.1778)
							(mid 0.137521 0.162921)
							(end 0.1524 0.127)
						)
					)
					(width 0)
					(fill yes)
				)
			)
		)
	)
	(footprint ""
		(layer "F.Cu")
		(at 308.748938 -64.77381)
		(property "Reference" "R362"
			(at 0 0 0)
			(layer "F.SilkS")
			(hide yes)
			(effects
				(font
					(size 1.27 1.27)
				)
			)
		)
		(property "Value" "4K7R2F-GP"
			(at 0.064008 -3.993896 0)
			(unlocked yes)
			(layer "F.Fab")
			(hide yes)
			(effects
				(font
					(size 1.016 1.016)
					(thickness 0.1524)
				)
			)
		)
		(property "Device Type" "R402H16"
			(at 0.064008 -5.517896 0)
			(unlocked yes)
			(layer "F.Fab")
			(hide yes)
			(effects
				(font
					(size 1.016 1.016)
					(thickness 0.1524)
				)
			)
		)
		(duplicate_pad_numbers_are_jumpers no)
		(fp_line
			(start -0.508 -0.9398)
			(end -0.508 0.9398)
			(stroke
				(width 0.1524)
				(type default)
			)
			(layer "F.SilkS")
		)
		(fp_line
			(start 0.508 -0.9398)
			(end -0.508 -0.9398)
			(stroke
				(width 0.1524)
				(type default)
			)
			(layer "F.SilkS")
		)
		(fp_rect
			(start -0.508 0.9398)
			(end 0.508 -0.9398)
			(stroke
				(width 0)
				(type default)
			)
			(fill no)
			(layer "F.CrtYd")
		)
		(fp_rect
			(start -0.508 0.9398)
			(end 0.508 -0.9398)
			(stroke
				(width 0)
				(type default)
			)
			(fill no)
			(layer "F.Fab")
		)
		(pad "1" smd custom
			(at 0 -0.4445)
			(size 0.1397 0.1397)
			(layers "F.Cu" "F.Mask" "F.Paste")
			(net "COMP_B_FAST_THROTTLE_N")
			(options
				(clearance outline)
				(anchor circle)
			)
			(primitives
				(gr_poly
					(pts
						(arc
							(start -0.1778 -0.2794)
							(mid -0.249642 -0.249642)
							(end -0.2794 -0.1778)
						)
						(arc
							(start -0.2794 0.1778)
							(mid -0.249642 0.249642)
							(end -0.1778 0.2794)
						)
						(arc
							(start 0.1778 0.2794)
							(mid 0.249642 0.249642)
							(end 0.2794 0.1778)
						)
						(arc
							(start 0.2794 -0.1778)
							(mid 0.249642 -0.249642)
							(end 0.1778 -0.2794)
						)
					)
					(width 0)
					(fill yes)
				)
			)
		)
		(pad "2" smd custom
			(at 0 0.4445)
			(size 0.1397 0.1397)
			(layers "F.Cu" "F.Mask" "F.Paste")
			(net "P3V3_STBY_B")
			(options
				(clearance outline)
				(anchor circle)
			)
			(primitives
				(gr_poly
					(pts
						(arc
							(start -0.1778 -0.2794)
							(mid -0.249642 -0.249642)
							(end -0.2794 -0.1778)
						)
						(arc
							(start -0.2794 0.1778)
							(mid -0.249642 0.249642)
							(end -0.1778 0.2794)
						)
						(arc
							(start 0.1778 0.2794)
							(mid 0.249642 0.249642)
							(end 0.2794 0.1778)
						)
						(arc
							(start 0.2794 -0.1778)
							(mid 0.249642 -0.249642)
							(end 0.1778 -0.2794)
						)
					)
					(width 0)
					(fill yes)
				)
			)
		)
	)
	(footprint ""
		(layer "F.Cu")
		(at 98.897948 -176.127918 90)
		(property "Reference" "C226"
			(at 0 0 90)
			(layer "F.SilkS")
			(hide yes)
			(effects
				(font
					(size 1.27 1.27)
				)
			)
		)
		(property "Value" "SCD01U50V2KX-1GP"
			(at 1.1811 -2.7051 90)
			(unlocked yes)
			(layer "F.Fab")
			(hide yes)
			(effects
				(font
					(size 1.016 1.016)
					(thickness 0.1524)
				)
			)
		)
		(property "Device Type" "C402H22"
			(at 1.1811 -4.2291 90)
			(unlocked yes)
			(layer "F.Fab")
			(hide yes)
			(effects
				(font
					(size 1.016 1.016)
					(thickness 0.1524)
				)
			)
		)
		(duplicate_pad_numbers_are_jumpers no)
		(fp_rect
			(start -0.4318 0.9525)
			(end 0.4318 -0.9525)
			(stroke
				(width 0)
				(type default)
			)
			(fill no)
			(layer "F.CrtYd")
		)
		(fp_rect
			(start -0.4318 0.9525)
			(end 0.4318 -0.9525)
			(stroke
				(width 0)
				(type default)
			)
			(fill no)
			(layer "F.Fab")
		)
		(pad "1" smd custom
			(at 0 -0.4445 90)
			(size 0.1524 0.1524)
			(layers "F.Cu" "F.Mask" "F.Paste")
			(net "HDD_PRSNT_14")
			(options
				(clearance outline)
				(anchor circle)
			)
			(primitives
				(gr_poly
					(pts
						(arc
							(start 0.3048 -0.2032)
							(mid 0.275042 -0.275042)
							(end 0.2032 -0.3048)
						)
						(arc
							(start -0.2032 -0.3048)
							(mid -0.275042 -0.275042)
							(end -0.3048 -0.2032)
						)
						(arc
							(start -0.3048 0.2032)
							(mid -0.275042 0.275042)
							(end -0.2032 0.3048)
						)
						(arc
							(start 0.2032 0.3048)
							(mid 0.275042 0.275042)
							(end 0.3048 0.2032)
						)
					)
					(width 0)
					(fill yes)
				)
			)
		)
		(pad "2" smd custom
			(at 0 0.4445 90)
			(size 0.1524 0.1524)
			(layers "F.Cu" "F.Mask" "F.Paste")
			(net "GND")
			(options
				(clearance outline)
				(anchor circle)
			)
			(primitives
				(gr_poly
					(pts
						(arc
							(start 0.3048 -0.2032)
							(mid 0.275042 -0.275042)
							(end 0.2032 -0.3048)
						)
						(arc
							(start -0.2032 -0.3048)
							(mid -0.275042 -0.275042)
							(end -0.3048 -0.2032)
						)
						(arc
							(start -0.3048 0.2032)
							(mid -0.275042 0.275042)
							(end -0.2032 0.3048)
						)
						(arc
							(start 0.2032 0.3048)
							(mid 0.275042 0.275042)
							(end 0.3048 0.2032)
						)
					)
					(width 0)
					(fill yes)
				)
			)
		)
	)
	(footprint ""
		(layer "F.Cu")
		(at 285.5214 -284.5308 180)
		(property "Reference" "R124"
			(at 0 0 180)
			(layer "F.SilkS")
			(hide yes)
			(effects
				(font
					(size 1.27 1.27)
				)
			)
		)
		(property "Value" "4K7R2F-GP"
			(at 0.064008 -3.993896 180)
			(unlocked yes)
			(layer "F.Fab")
			(hide yes)
			(effects
				(font
					(size 1.016 1.016)
					(thickness 0.1524)
				)
			)
		)
		(property "Device Type" "R402H16"
			(at 0.064008 -5.517896 180)
			(unlocked yes)
			(layer "F.Fab")
			(hide yes)
			(effects
				(font
					(size 1.016 1.016)
					(thickness 0.1524)
				)
			)
		)
		(duplicate_pad_numbers_are_jumpers no)
		(fp_line
			(start 0.508 -0.9398)
			(end -0.508 -0.9398)
			(stroke
				(width 0.1524)
				(type default)
			)
			(layer "F.SilkS")
		)
		(fp_line
			(start -0.508 -0.9398)
			(end -0.508 0.9398)
			(stroke
				(width 0.1524)
				(type default)
			)
			(layer "F.SilkS")
		)
		(fp_rect
			(start -0.508 0.9398)
			(end 0.508 -0.9398)
			(stroke
				(width 0)
				(type default)
			)
			(fill no)
			(layer "F.CrtYd")
		)
		(fp_rect
			(start -0.508 0.9398)
			(end 0.508 -0.9398)
			(stroke
				(width 0)
				(type default)
			)
			(fill no)
			(layer "F.Fab")
		)
		(pad "1" smd custom
			(at 0 -0.4445 180)
			(size 0.1397 0.1397)
			(layers "F.Cu" "F.Mask" "F.Paste")
			(net "IO_EXP2_HDD_FAULT_A0")
			(options
				(clearance outline)
				(anchor circle)
			)
			(primitives
				(gr_poly
					(pts
						(arc
							(start -0.1778 -0.2794)
							(mid -0.249642 -0.249642)
							(end -0.2794 -0.1778)
						)
						(arc
							(start -0.2794 0.1778)
							(mid -0.249642 0.249642)
							(end -0.1778 0.2794)
						)
						(arc
							(start 0.1778 0.2794)
							(mid 0.249642 0.249642)
							(end 0.2794 0.1778)
						)
						(arc
							(start 0.2794 -0.1778)
							(mid 0.249642 -0.249642)
							(end 0.1778 -0.2794)
						)
					)
					(width 0)
					(fill yes)
				)
			)
		)
		(pad "2" smd custom
			(at 0 0.4445 180)
			(size 0.1397 0.1397)
			(layers "F.Cu" "F.Mask" "F.Paste")
			(net "GND")
			(options
				(clearance outline)
				(anchor circle)
			)
			(primitives
				(gr_poly
					(pts
						(arc
							(start -0.1778 -0.2794)
							(mid -0.249642 -0.249642)
							(end -0.2794 -0.1778)
						)
						(arc
							(start -0.2794 0.1778)
							(mid -0.249642 0.249642)
							(end -0.1778 0.2794)
						)
						(arc
							(start 0.1778 0.2794)
							(mid 0.249642 0.249642)
							(end 0.2794 0.1778)
						)
						(arc
							(start 0.2794 -0.1778)
							(mid 0.249642 -0.249642)
							(end 0.1778 -0.2794)
						)
					)
					(width 0)
					(fill yes)
				)
			)
		)
	)
	(footprint ""
		(layer "F.Cu")
		(at 338.709 -172.851318 90)
		(property "Reference" "C283"
			(at 0 0 90)
			(layer "F.SilkS")
			(hide yes)
			(effects
				(font
					(size 1.27 1.27)
				)
			)
		)
		(property "Value" "SCD033U25V2KX-GP"
			(at 1.1811 -2.7051 90)
			(unlocked yes)
			(layer "F.Fab")
			(hide yes)
			(effects
				(font
					(size 1.016 1.016)
					(thickness 0.1524)
				)
			)
		)
		(property "Device Type" "C402H22"
			(at 1.1811 -4.2291 90)
			(unlocked yes)
			(layer "F.Fab")
			(hide yes)
			(effects
				(font
					(size 1.016 1.016)
					(thickness 0.1524)
				)
			)
		)
		(duplicate_pad_numbers_are_jumpers no)
		(fp_rect
			(start -0.4318 0.9525)
			(end 0.4318 -0.9525)
			(stroke
				(width 0)
				(type default)
			)
			(fill no)
			(layer "F.CrtYd")
		)
		(fp_rect
			(start -0.4318 0.9525)
			(end 0.4318 -0.9525)
			(stroke
				(width 0)
				(type default)
			)
			(fill no)
			(layer "F.Fab")
		)
		(pad "1" smd custom
			(at 0 -0.4445 90)
			(size 0.1524 0.1524)
			(layers "F.Cu" "F.Mask" "F.Paste")
			(net "P12V_A")
			(options
				(clearance outline)
				(anchor circle)
			)
			(primitives
				(gr_poly
					(pts
						(arc
							(start 0.3048 -0.2032)
							(mid 0.275042 -0.275042)
							(end 0.2032 -0.3048)
						)
						(arc
							(start -0.2032 -0.3048)
							(mid -0.275042 -0.275042)
							(end -0.3048 -0.2032)
						)
						(arc
							(start -0.3048 0.2032)
							(mid -0.275042 0.275042)
							(end -0.2032 0.3048)
						)
						(arc
							(start 0.2032 0.3048)
							(mid 0.275042 0.275042)
							(end 0.3048 0.2032)
						)
					)
					(width 0)
					(fill yes)
				)
			)
		)
		(pad "2" smd custom
			(at 0 0.4445 90)
			(size 0.1524 0.1524)
			(layers "F.Cu" "F.Mask" "F.Paste")
			(net "SW_HDD_N18")
			(options
				(clearance outline)
				(anchor circle)
			)
			(primitives
				(gr_poly
					(pts
						(arc
							(start 0.3048 -0.2032)
							(mid 0.275042 -0.275042)
							(end 0.2032 -0.3048)
						)
						(arc
							(start -0.2032 -0.3048)
							(mid -0.275042 -0.275042)
							(end -0.3048 -0.2032)
						)
						(arc
							(start -0.3048 0.2032)
							(mid -0.275042 0.275042)
							(end -0.2032 0.3048)
						)
						(arc
							(start 0.2032 0.3048)
							(mid 0.275042 0.275042)
							(end 0.3048 0.2032)
						)
					)
					(width 0)
					(fill yes)
				)
			)
		)
	)
	(footprint ""
		(layer "F.Cu")
		(at 428.26686 -299.435266 -90)
		(property "Reference" "R340"
			(at 0 0 270)
			(layer "F.SilkS")
			(hide yes)
			(effects
				(font
					(size 1.27 1.27)
				)
			)
		)
		(property "Value" "2R6F-GP"
			(at -0.0508 -4.8514 270)
			(unlocked yes)
			(layer "F.Fab")
			(hide yes)
			(effects
				(font
					(size 1.016 1.016)
					(thickness 0.1524)
				)
			)
		)
		(property "Device Type" "R1206H26"
			(at 0 -6.3754 270)
			(unlocked yes)
			(layer "F.Fab")
			(hide yes)
			(effects
				(font
					(size 1.016 1.016)
					(thickness 0.1524)
				)
			)
		)
		(duplicate_pad_numbers_are_jumpers no)
		(fp_line
			(start -1.016 2.2352)
			(end -1.016 -2.2352)
			(stroke
				(width 0.1524)
				(type default)
			)
			(layer "F.SilkS")
		)
		(fp_line
			(start 1.016 2.2352)
			(end -1.016 2.2352)
			(stroke
				(width 0.1524)
				(type default)
			)
			(layer "F.SilkS")
		)
		(fp_line
			(start -1.016 -2.2352)
			(end 1.016 -2.2352)
			(stroke
				(width 0.1524)
				(type default)
			)
			(layer "F.SilkS")
		)
		(fp_line
			(start 1.016 -2.2352)
			(end 1.016 2.2352)
			(stroke
				(width 0.1524)
				(type default)
			)
			(layer "F.SilkS")
		)
		(fp_rect
			(start -1.0922 2.3114)
			(end 1.0922 -2.3114)
			(stroke
				(width 0)
				(type default)
			)
			(fill no)
			(layer "F.CrtYd")
		)
		(fp_poly
			(pts
				(xy -1.0922 -2.3114) (xy 1.0922 -2.3114) (xy 1.0922 2.3114) (xy -1.0922 2.3114)
			)
			(stroke
				(width 0)
				(type default)
			)
			(fill no)
			(layer "F.Fab")
		)
		(pad "1" smd rect
			(at 0 -1.397 270)
			(size 1.651 1.27)
			(layers "F.Cu" "F.Mask" "F.Paste")
			(net "P12V_HDD9")
		)
		(pad "2" smd rect
			(at 0 1.397 270)
			(size 1.651 1.27)
			(layers "F.Cu" "F.Mask" "F.Paste")
			(net "12V_PRE_9")
		)
	)
	(footprint ""
		(layer "F.Cu")
		(at 241.775488 -346.354908)
		(property "Reference" "R182"
			(at 0 0 0)
			(layer "F.SilkS")
			(hide yes)
			(effects
				(font
					(size 1.27 1.27)
				)
			)
		)
		(property "Value" "16K2R2F-GP"
			(at 0.064008 -3.993896 0)
			(unlocked yes)
			(layer "F.Fab")
			(hide yes)
			(effects
				(font
					(size 1.016 1.016)
					(thickness 0.1524)
				)
			)
		)
		(property "Device Type" "R402H16"
			(at 0.064008 -5.517896 0)
			(unlocked yes)
			(layer "F.Fab")
			(hide yes)
			(effects
				(font
					(size 1.016 1.016)
					(thickness 0.1524)
				)
			)
		)
		(duplicate_pad_numbers_are_jumpers no)
		(fp_line
			(start -0.508 -0.9398)
			(end -0.508 0.9398)
			(stroke
				(width 0.1524)
				(type default)
			)
			(layer "F.SilkS")
		)
		(fp_line
			(start 0.508 -0.9398)
			(end -0.508 -0.9398)
			(stroke
				(width 0.1524)
				(type default)
			)
			(layer "F.SilkS")
		)
		(fp_rect
			(start -0.508 0.9398)
			(end 0.508 -0.9398)
			(stroke
				(width 0)
				(type default)
			)
			(fill no)
			(layer "F.CrtYd")
		)
		(fp_rect
			(start -0.508 0.9398)
			(end 0.508 -0.9398)
			(stroke
				(width 0)
				(type default)
			)
			(fill no)
			(layer "F.Fab")
		)
		(pad "1" smd custom
			(at 0 -0.4445)
			(size 0.1397 0.1397)
			(layers "F.Cu" "F.Mask" "F.Paste")
			(net "P5V_A_3")
			(options
				(clearance outline)
				(anchor circle)
			)
			(primitives
				(gr_poly
					(pts
						(arc
							(start -0.1778 -0.2794)
							(mid -0.249642 -0.249642)
							(end -0.2794 -0.1778)
						)
						(arc
							(start -0.2794 0.1778)
							(mid -0.249642 0.249642)
							(end -0.1778 0.2794)
						)
						(arc
							(start 0.1778 0.2794)
							(mid 0.249642 0.249642)
							(end 0.2794 0.1778)
						)
						(arc
							(start 0.2794 -0.1778)
							(mid 0.249642 -0.249642)
							(end 0.1778 -0.2794)
						)
					)
					(width 0)
					(fill yes)
				)
			)
		)
		(pad "2" smd custom
			(at 0 0.4445)
			(size 0.1397 0.1397)
			(layers "F.Cu" "F.Mask" "F.Paste")
			(net "P5V_A_3_SENSE")
			(options
				(clearance outline)
				(anchor circle)
			)
			(primitives
				(gr_poly
					(pts
						(arc
							(start -0.1778 -0.2794)
							(mid -0.249642 -0.249642)
							(end -0.2794 -0.1778)
						)
						(arc
							(start -0.2794 0.1778)
							(mid -0.249642 0.249642)
							(end -0.1778 0.2794)
						)
						(arc
							(start 0.1778 0.2794)
							(mid 0.249642 0.249642)
							(end 0.2794 0.1778)
						)
						(arc
							(start 0.2794 -0.1778)
							(mid 0.249642 -0.249642)
							(end 0.1778 -0.2794)
						)
					)
					(width 0)
					(fill yes)
				)
			)
		)
	)
)
